# BASEBOARD_FAB2 (Tioga Pass) — schematic netlist excerpt (pin names and nets, part order shuffled) for the footprints in the layout excerpt that follows; sources: Cadence DE-HDL packaged netlist, KiCad conversion of Wiwynn_Tioga_Pass_MB.brd

C4F9  CAP_A  0.01UF 25V 10% X7R  pkg 0402V  page 98 : A = M_A_CPU_VREF ; B = GND
CR8E1  DIODE  BAT54WS IC  pkg SMLF  page 196 : C = PWRGD_P12V_HSC ; A = PWRGD_P12V_HSC_DLY
C2A10  CAP_A  47UF 4V 20% X5R  pkg 0603V  page 228 : A = PVDDQ_KLM ; B = GND

(kicad_pcb
	(version 20260206)
	(generator "pcbnew")
	(generator_version "10.0")
	(general
		(thickness 1.6)
		(legacy_teardrops no)
	)
	(paper "A4")
	(title_block
		(title "Wiwynn_Tioga_Pass_MB.brd")
		(comment 1 "Tioga Pass / footprints 1859-1861 of 4770")
	)
	(layers
		(0 "F.Cu" signal "TOP")
		(4 "In1.Cu" signal "L2GND")
		(6 "In2.Cu" signal "L3")
		(8 "In3.Cu" signal "L4GND")
		(10 "In4.Cu" signal "L5")
		(12 "In5.Cu" signal "L6GND")
		(14 "In6.Cu" signal "L7VCC")
		(16 "In7.Cu" signal "L8VCC")
		(18 "In8.Cu" signal "L9GND")
		(20 "In9.Cu" signal "L10")
		(22 "In10.Cu" signal "L11GND")
		(24 "In11.Cu" signal "L12")
		(26 "In12.Cu" signal "L13GND")
		(2 "B.Cu" signal "BOTTOM")
		(9 "F.Adhes" user "F.Adhesive")
		(11 "B.Adhes" user "B.Adhesive")
		(13 "F.Paste" user "Package Geometry/Pastemask Top")
		(15 "B.Paste" user "Package Geometry/Pastemask Bottom")
		(5 "F.SilkS" user "Ref Des/Silkscreen Top")
		(7 "B.SilkS" user "Ref Des/Silkscreen Bottom")
		(1 "F.Mask" user "Board Geometry/Soldermask Top")
		(3 "B.Mask" user "Board Geometry/Soldermask Bottom")
		(17 "Dwgs.User" user "User.Drawings")
		(19 "Cmts.User" user "User.Comments")
		(21 "Eco1.User" user "User.Eco1")
		(23 "Eco2.User" user "User.Eco2")
		(25 "Edge.Cuts" user "Board Geometry/Outline")
		(27 "Margin" user)
		(31 "F.CrtYd" user "Package Geometry/Place Bound Top")
		(29 "B.CrtYd" user "Package Geometry/Place Bound Bottom")
		(35 "F.Fab" user "Ref Des/Assembly Top")
		(33 "B.Fab" user "Ref Des/Assembly Bottom")
	)
	(footprint ""
		(layer "F.Cu")
		(at 83.856068 -140.208 -90)
		(property "Reference" "C2A10"
			(at 1.848866 0.752348 270)
			(unlocked yes)
			(layer "F.SilkS")
			(effects
				(font
					(size 1.27 0.9652)
					(thickness 0.1524)
				)
			)
		)
		(property "Value" ""
			(at 0 0 270)
			(layer "F.Fab")
			(effects
				(font
					(size 1.27 1.27)
				)
			)
		)
		(duplicate_pad_numbers_are_jumpers no)
		(fp_rect
			(start -0.500126 1.598422)
			(end 0.500126 -0.201422)
			(stroke
				(width 0)
				(type default)
			)
			(fill no)
			(layer "F.CrtYd")
		)
		(fp_line
			(start -0.500126 1.598422)
			(end -0.500126 -0.201422)
			(stroke
				(width 0.1)
				(type default)
			)
			(layer "F.Fab")
		)
		(fp_line
			(start 0.500126 1.598422)
			(end -0.500126 1.598422)
			(stroke
				(width 0.1)
				(type default)
			)
			(layer "F.Fab")
		)
		(fp_line
			(start -0.500126 -0.201422)
			(end 0.500126 -0.201422)
			(stroke
				(width 0.1)
				(type default)
			)
			(layer "F.Fab")
		)
		(fp_line
			(start 0.500126 -0.201422)
			(end 0.500126 1.598422)
			(stroke
				(width 0.1)
				(type default)
			)
			(layer "F.Fab")
		)
		(pad "1" smd rect
			(at 0 0 180)
			(size 0.889 0.9906)
			(layers "F.Cu" "F.Mask" "F.Paste")
			(net "PVDDQ_KLM")
		)
		(pad "2" smd rect
			(at 0 1.397 180)
			(size 0.889 0.9906)
			(layers "F.Cu" "F.Mask" "F.Paste")
			(net "GND")
		)
		(zone
			(layer "F.Cu")
			(hatch none 0.5)
			(connect_pads
				(clearance 0)
			)
			(min_thickness 0.25)
			(keepout
				(tracks not_allowed)
				(vias allowed)
				(pads allowed)
				(copperpour not_allowed)
				(footprints allowed)
			)
			(placement
				(enabled no)
				(sheetname "")
			)
			(fill
				(thermal_gap 0.5)
				(thermal_bridge_width 0.5)
				(island_removal_mode 0)
			)
			(polygon
				(pts
					(xy 82.903568 -140.7033) (xy 82.903568 -139.7127) (xy 83.411568 -139.7127) (xy 83.411568 -140.7033)
				)
			)
		)
		(zone
			(layer "F.Cu")
			(hatch none 0.5)
			(connect_pads
				(clearance 0)
			)
			(min_thickness 0.25)
			(keepout
				(tracks allowed)
				(vias not_allowed)
				(pads allowed)
				(copperpour not_allowed)
				(footprints allowed)
			)
			(placement
				(enabled no)
				(sheetname "")
			)
			(fill
				(thermal_gap 0.5)
				(thermal_bridge_width 0.5)
				(island_removal_mode 0)
			)
			(polygon
				(pts
					(xy 82.903568 -140.7033) (xy 82.903568 -139.7127) (xy 83.411568 -139.7127) (xy 83.411568 -140.7033)
				)
			)
		)
	)
	(footprint ""
		(layer "F.Cu")
		(at 191.897 -23.396194)
		(property "Reference" "C4F9"
			(at 0 0 0)
			(layer "F.SilkS")
			(hide yes)
			(effects
				(font
					(size 1.27 1.27)
				)
			)
		)
		(property "Value" ""
			(at 0 0 0)
			(layer "F.Fab")
			(effects
				(font
					(size 1.27 1.27)
				)
			)
		)
		(duplicate_pad_numbers_are_jumpers no)
		(fp_poly
			(pts
				(xy 0.3048 -0.1016) (xy 0.3048 0.9906) (xy -0.3048 0.9906) (xy -0.3048 -0.1016)
			)
			(stroke
				(width 0)
				(type default)
			)
			(fill no)
			(layer "F.CrtYd")
		)
		(fp_line
			(start -0.3048 -0.1016)
			(end -0.3048 0.9906)
			(stroke
				(width 0.1)
				(type default)
			)
			(layer "F.Fab")
		)
		(fp_line
			(start -0.3048 0.9906)
			(end 0.3048 0.9906)
			(stroke
				(width 0.1)
				(type default)
			)
			(layer "F.Fab")
		)
		(fp_line
			(start 0.3048 -0.1016)
			(end -0.3048 -0.1016)
			(stroke
				(width 0.1)
				(type default)
			)
			(layer "F.Fab")
		)
		(fp_line
			(start 0.3048 0.9906)
			(end 0.3048 -0.1016)
			(stroke
				(width 0.1)
				(type default)
			)
			(layer "F.Fab")
		)
		(pad "1" smd rect
			(at 0 0)
			(size 0.508 0.508)
			(layers "F.Cu" "F.Mask" "F.Paste")
			(net "M_A_CPU_VREF")
		)
		(pad "2" smd rect
			(at 0 0.889)
			(size 0.508 0.508)
			(layers "F.Cu" "F.Mask" "F.Paste")
			(net "GND")
		)
		(zone
			(layer "F.Cu")
			(hatch none 0.5)
			(connect_pads
				(clearance 0)
			)
			(min_thickness 0.25)
			(keepout
				(tracks allowed)
				(vias not_allowed)
				(pads allowed)
				(copperpour not_allowed)
				(footprints allowed)
			)
			(placement
				(enabled no)
				(sheetname "")
			)
			(fill
				(thermal_gap 0.5)
				(thermal_bridge_width 0.5)
				(island_removal_mode 0)
			)
			(polygon
				(pts
					(xy 191.643 -23.142194) (xy 192.151 -23.142194) (xy 192.151 -22.761194) (xy 191.643 -22.761194)
				)
			)
		)
		(zone
			(layer "F.Cu")
			(hatch none 0.5)
			(connect_pads
				(clearance 0)
			)
			(min_thickness 0.25)
			(keepout
				(tracks not_allowed)
				(vias allowed)
				(pads allowed)
				(copperpour not_allowed)
				(footprints allowed)
			)
			(placement
				(enabled no)
				(sheetname "")
			)
			(fill
				(thermal_gap 0.5)
				(thermal_bridge_width 0.5)
				(island_removal_mode 0)
			)
			(polygon
				(pts
					(xy 191.643 -22.761194) (xy 192.151 -22.761194) (xy 192.151 -23.142194) (xy 191.643 -23.142194)
				)
			)
		)
	)
	(footprint ""
		(layer "F.Cu")
		(at 399.542 -77.089 180)
		(property "Reference" "CR8E1"
			(at 1.49733 1.4478 90)
			(unlocked yes)
			(layer "F.SilkS")
			(effects
				(font
					(size 0.7874 0.5842)
					(thickness 0.1524)
				)
				(justify left)
			)
		)
		(property "Value" ""
			(at 0 0 180)
			(layer "F.Fab")
			(effects
				(font
					(size 1.27 1.27)
				)
			)
		)
		(duplicate_pad_numbers_are_jumpers no)
		(fp_line
			(start -0.798576 1.649222)
			(end -1.279398 1.649222)
			(stroke
				(width 0.1524)
				(type default)
			)
			(layer "F.SilkS")
		)
		(fp_line
			(start -0.798576 0.816356)
			(end -1.76022 0.816356)
			(stroke
				(width 0.1524)
				(type default)
			)
			(layer "F.SilkS")
		)
		(fp_line
			(start -1.279398 2.560828)
			(end -1.279398 1.649222)
			(stroke
				(width 0.1524)
				(type default)
			)
			(layer "F.SilkS")
		)
		(fp_line
			(start -1.279398 1.649222)
			(end -1.76022 1.649222)
			(stroke
				(width 0.1524)
				(type default)
			)
			(layer "F.SilkS")
		)
		(fp_line
			(start -1.279398 0.816356)
			(end -0.798576 1.649222)
			(stroke
				(width 0.1524)
				(type default)
			)
			(layer "F.SilkS")
		)
		(fp_line
			(start -1.279398 -0.307086)
			(end -1.279398 0.816356)
			(stroke
				(width 0.1524)
				(type default)
			)
			(layer "F.SilkS")
		)
		(fp_line
			(start -1.76022 1.649222)
			(end -1.279398 0.816356)
			(stroke
				(width 0.1524)
				(type default)
			)
			(layer "F.SilkS")
		)
		(fp_poly
			(pts
				(xy -0.67437 0.24384) (xy -0.67437 2.04216) (xy 0.67437 2.04216) (xy 0.67437 0.24384)
			)
			(stroke
				(width 0)
				(type default)
			)
			(fill no)
			(layer "F.CrtYd")
		)
		(fp_line
			(start 0.67437 2.04216)
			(end 0.67437 0.24384)
			(stroke
				(width 0.1)
				(type default)
			)
			(layer "F.Fab")
		)
		(fp_line
			(start 0.67437 0.24384)
			(end -0.67437 0.24384)
			(stroke
				(width 0.1)
				(type default)
			)
			(layer "F.Fab")
		)
		(fp_line
			(start -0.67437 2.04216)
			(end 0.67437 2.04216)
			(stroke
				(width 0.1)
				(type default)
			)
			(layer "F.Fab")
		)
		(fp_line
			(start -0.67437 0.24384)
			(end -0.67437 2.04216)
			(stroke
				(width 0.1)
				(type default)
			)
			(layer "F.Fab")
		)
		(fp_line
			(start -0.803656 1.664462)
			(end -1.7653 1.664462)
			(stroke
				(width 0.1)
				(type default)
			)
			(layer "F.Fab")
		)
		(fp_line
			(start -0.854456 0.831596)
			(end -1.8161 0.831596)
			(stroke
				(width 0.1)
				(type default)
			)
			(layer "F.Fab")
		)
		(fp_line
			(start -1.284478 1.664462)
			(end -1.284478 2.576068)
			(stroke
				(width 0.1)
				(type default)
			)
			(layer "F.Fab")
		)
		(fp_line
			(start -1.284478 0.831596)
			(end -0.803656 1.664462)
			(stroke
				(width 0.1)
				(type default)
			)
			(layer "F.Fab")
		)
		(fp_line
			(start -1.335278 0.831596)
			(end -1.335278 -0.291846)
			(stroke
				(width 0.1)
				(type default)
			)
			(layer "F.Fab")
		)
		(fp_line
			(start -1.7653 1.664462)
			(end -1.284478 0.831596)
			(stroke
				(width 0.1)
				(type default)
			)
			(layer "F.Fab")
		)
		(pad "1" smd rect
			(at 0 0 180)
			(size 0.4064 1.016)
			(layers "F.Cu" "F.Mask" "F.Paste")
			(net "PWRGD_P12V_HSC")
		)
		(pad "2" smd rect
			(at 0 2.286 180)
			(size 0.4064 1.016)
			(layers "F.Cu" "F.Mask" "F.Paste")
			(net "PWRGD_P12V_HSC_DLY")
		)
	)
)
